# SCM (Grand Teton) — schematic netlist excerpt (pin names and nets, part order shuffled) for the footprints in the layout excerpt that follows; sources: Cadence DE-HDL packaged netlist, KiCad conversion of 12092022_DA0F0TMDCD0_F0T_Management_Board_D_brd_V3_OCP.brd

D22  Q_LED  IC  pkg THLF  page 50 : A = LED_D22_R ; C = LED_D22_R1
R132  Q_RES  33.2 1% CHIP  pkg 0402LF  page 12 : A = SMB_BMC_MM1_R_SCL ; B = SMB_BMC_MM1_SCL

(kicad_pcb
	(version 20260206)
	(generator "pcbnew")
	(generator_version "10.0")
	(general
		(thickness 1.6)
		(legacy_teardrops no)
	)
	(paper "A4")
	(title_block
		(title "12092022_DA0F0TMDCD0_F0T_Management_Board_D_brd_V3_OCP.brd")
		(comment 1 "Grand Teton / footprints 229-230 of 1440")
	)
	(layers
		(0 "F.Cu" signal "TOP")
		(4 "In1.Cu" signal "GND")
		(6 "In2.Cu" signal "IN1")
		(8 "In3.Cu" signal "GND1")
		(10 "In4.Cu" signal "IN2")
		(12 "In5.Cu" signal "VCC")
		(14 "In6.Cu" signal "VCC1")
		(16 "In7.Cu" signal "IN3")
		(18 "In8.Cu" signal "GND2")
		(20 "In9.Cu" signal "IN4")
		(22 "In10.Cu" signal "GND3")
		(2 "B.Cu" signal "BOTTOM")
		(9 "F.Adhes" user "F.Adhesive")
		(11 "B.Adhes" user "B.Adhesive")
		(13 "F.Paste" user "Package Geometry/Pastemask Top")
		(15 "B.Paste" user "Package Geometry/Pastemask Bottom")
		(5 "F.SilkS" user "Ref Des/Silkscreen Top")
		(7 "B.SilkS" user "Ref Des/Silkscreen Bottom")
		(1 "F.Mask" user "Board Geometry/Soldermask Top")
		(3 "B.Mask" user "Board Geometry/Soldermask Bottom")
		(17 "Dwgs.User" user "User.Drawings")
		(19 "Cmts.User" user "User.Comments")
		(21 "Eco1.User" user "User.Eco1")
		(23 "Eco2.User" user "User.Eco2")
		(25 "Edge.Cuts" user "Board Geometry/Outline")
		(27 "Margin" user)
		(31 "F.CrtYd" user "Package Geometry/Place Bound Top")
		(29 "B.CrtYd" user "Package Geometry/Place Bound Bottom")
		(35 "F.Fab" user "Ref Des/Assembly Top")
		(33 "B.Fab" user "Ref Des/Assembly Bottom")
	)
	(footprint ""
		(layer "F.Cu")
		(at 60.380118 -6.290056)
		(property "Reference" "D22"
			(at -1.143 -2.708148 0)
			(unlocked yes)
			(layer "F.SilkS")
			(effects
				(font
					(size 0.7874 0.5842)
					(thickness 0.1524)
				)
				(justify left)
			)
		)
		(property "Value" ""
			(at 0 0 0)
			(layer "F.Fab")
			(effects
				(font
					(size 1.27 1.27)
				)
			)
		)
		(duplicate_pad_numbers_are_jumpers no)
		(fp_line
			(start -1.080008 -1.999996)
			(end 3.620008 -1.999996)
			(stroke
				(width 0.1524)
				(type default)
			)
			(layer "F.SilkS")
		)
		(fp_line
			(start -1.080008 3.999992)
			(end -1.080008 -1.999996)
			(stroke
				(width 0.1524)
				(type default)
			)
			(layer "F.SilkS")
		)
		(fp_line
			(start -0.230124 3.999992)
			(end -1.080008 3.999992)
			(stroke
				(width 0.1524)
				(type default)
			)
			(layer "F.SilkS")
		)
		(fp_line
			(start -0.230124 5.199888)
			(end -0.230124 3.999992)
			(stroke
				(width 0.1524)
				(type default)
			)
			(layer "F.SilkS")
		)
		(fp_line
			(start 2.770124 3.999992)
			(end 2.770124 5.199888)
			(stroke
				(width 0.1524)
				(type default)
			)
			(layer "F.SilkS")
		)
		(fp_line
			(start 3.620008 -1.999996)
			(end 3.620008 3.999992)
			(stroke
				(width 0.1524)
				(type default)
			)
			(layer "F.SilkS")
		)
		(fp_line
			(start 3.620008 3.999992)
			(end 2.770124 3.999992)
			(stroke
				(width 0.1524)
				(type default)
			)
			(layer "F.SilkS")
		)
		(fp_arc
			(start 1.27 6.700012)
			(mid 0.209252 6.260636)
			(end -0.230124 5.199888)
			(stroke
				(width 0.1524)
				(type default)
			)
			(layer "F.SilkS")
		)
		(fp_arc
			(start 2.770124 5.199888)
			(mid 2.330748 6.260636)
			(end 1.27 6.700012)
			(stroke
				(width 0.1524)
				(type default)
			)
			(layer "F.SilkS")
		)
		(fp_line
			(start -1.080008 -1.999996)
			(end 3.620008 -1.999996)
			(stroke
				(width 0.1)
				(type default)
			)
			(layer "F.Fab")
		)
		(fp_line
			(start -1.080008 3.999992)
			(end -1.080008 -1.999996)
			(stroke
				(width 0.1)
				(type default)
			)
			(layer "F.Fab")
		)
		(fp_line
			(start -0.230124 3.999992)
			(end -1.080008 3.999992)
			(stroke
				(width 0.1)
				(type default)
			)
			(layer "F.Fab")
		)
		(fp_line
			(start -0.230124 5.199888)
			(end -0.230124 3.999992)
			(stroke
				(width 0.1)
				(type default)
			)
			(layer "F.Fab")
		)
		(fp_line
			(start 2.770124 3.999992)
			(end 2.770124 5.199888)
			(stroke
				(width 0.1)
				(type default)
			)
			(layer "F.Fab")
		)
		(fp_line
			(start 3.620008 -1.999996)
			(end 3.620008 3.999992)
			(stroke
				(width 0.1)
				(type default)
			)
			(layer "F.Fab")
		)
		(fp_line
			(start 3.620008 3.999992)
			(end 2.770124 3.999992)
			(stroke
				(width 0.1)
				(type default)
			)
			(layer "F.Fab")
		)
		(fp_arc
			(start 1.27 6.700012)
			(mid 0.209252 6.260636)
			(end -0.230124 5.199888)
			(stroke
				(width 0.1)
				(type default)
			)
			(layer "F.Fab")
		)
		(fp_arc
			(start 2.770124 5.199888)
			(mid 2.330748 6.260636)
			(end 1.27 6.700012)
			(stroke
				(width 0.1)
				(type default)
			)
			(layer "F.Fab")
		)
		(pad "A" thru_hole rect
			(at 0 0)
			(size 1.2192 1.2192)
			(drill 0.8128)
			(layers "*.Cu" "*.Mask")
			(remove_unused_layers no)
			(net "LED_D22_R")
			(clearance 0.0508)
			(thermal_gap 0.0508)
			(padstack
				(mode front_inner_back)
				(layer "Inner"
					(shape circle)
					(size 1.2192 1.2192)
					(clearance 0.0508)
				)
				(layer "B.Cu"
					(shape rect)
					(size 1.2192 1.2192)
					(clearance 0.0508)
				)
			)
		)
		(pad "C" thru_hole circle
			(at 2.54 0)
			(size 1.2192 1.2192)
			(drill 0.8128)
			(layers "*.Cu" "*.Mask")
			(remove_unused_layers no)
			(net "LED_D22_R1")
			(clearance 0.0508)
			(thermal_gap 0.0508)
		)
	)
	(footprint ""
		(layer "F.Cu")
		(at 47.752 -34.6456 -90)
		(property "Reference" "R132"
			(at 0 0 270)
			(layer "F.SilkS")
			(hide yes)
			(effects
				(font
					(size 1.27 1.27)
				)
			)
		)
		(property "Value" ""
			(at 0 0 270)
			(layer "F.Fab")
			(effects
				(font
					(size 1.27 1.27)
				)
			)
		)
		(duplicate_pad_numbers_are_jumpers no)
		(fp_line
			(start -0.7874 0.4064)
			(end -0.7874 -0.4064)
			(stroke
				(width 0.1524)
				(type default)
			)
			(layer "F.SilkS")
		)
		(fp_line
			(start 0.7874 0.4064)
			(end -0.7874 0.4064)
			(stroke
				(width 0.1524)
				(type default)
			)
			(layer "F.SilkS")
		)
		(fp_line
			(start -0.7874 -0.4064)
			(end 0.7874 -0.4064)
			(stroke
				(width 0.1524)
				(type default)
			)
			(layer "F.SilkS")
		)
		(fp_line
			(start 0.7874 -0.4064)
			(end 0.7874 0.4064)
			(stroke
				(width 0.1524)
				(type default)
			)
			(layer "F.SilkS")
		)
		(fp_line
			(start -0.67945 0.3048)
			(end -0.67945 -0.305054)
			(stroke
				(width 0.1)
				(type default)
			)
			(layer "F.Fab")
		)
		(fp_line
			(start -0.12065 0.3048)
			(end -0.67945 0.3048)
			(stroke
				(width 0.1)
				(type default)
			)
			(layer "F.Fab")
		)
		(fp_line
			(start 0.120396 0.3048)
			(end 0.120396 0.2794)
			(stroke
				(width 0.1)
				(type default)
			)
			(layer "F.Fab")
		)
		(fp_line
			(start 0.67945 0.3048)
			(end 0.120396 0.3048)
			(stroke
				(width 0.1)
				(type default)
			)
			(layer "F.Fab")
		)
		(fp_line
			(start -0.12065 0.2794)
			(end -0.12065 0.3048)
			(stroke
				(width 0.1)
				(type default)
			)
			(layer "F.Fab")
		)
		(fp_line
			(start 0.120396 0.2794)
			(end -0.12065 0.2794)
			(stroke
				(width 0.1)
				(type default)
			)
			(layer "F.Fab")
		)
		(fp_line
			(start -0.12065 -0.2794)
			(end 0.12065 -0.2794)
			(stroke
				(width 0.1)
				(type default)
			)
			(layer "F.Fab")
		)
		(fp_line
			(start 0.12065 -0.2794)
			(end 0.12065 -0.3048)
			(stroke
				(width 0.1)
				(type default)
			)
			(layer "F.Fab")
		)
		(fp_line
			(start 0.12065 -0.3048)
			(end 0.67945 -0.3048)
			(stroke
				(width 0.1)
				(type default)
			)
			(layer "F.Fab")
		)
		(fp_line
			(start 0.67945 -0.3048)
			(end 0.67945 0.3048)
			(stroke
				(width 0.1)
				(type default)
			)
			(layer "F.Fab")
		)
		(fp_line
			(start -0.67945 -0.305054)
			(end -0.12065 -0.305054)
			(stroke
				(width 0.1)
				(type default)
			)
			(layer "F.Fab")
		)
		(fp_line
			(start -0.12065 -0.305054)
			(end -0.12065 -0.2794)
			(stroke
				(width 0.1)
				(type default)
			)
			(layer "F.Fab")
		)
		(pad "1" smd circle
			(at -0.40005 0 270)
			(size 0 0)
			(layers "F.Cu" "F.Mask" "F.Paste")
			(net "SMB_BMC_MM1_R_SCL")
		)
		(pad "2" smd circle
			(at 0.40005 0 270)
			(size 0 0)
			(layers "F.Cu" "F.Mask" "F.Paste")
			(net "SMB_BMC_MM1_SCL")
		)
	)
)
